# T6G (Grand Teton) — schematic netlist excerpt (pin names and nets, part order shuffled) for the footprints in the layout excerpt that follows; sources: Cadence DE-HDL packaged netlist, KiCad conversion of 04192023_DAF0TMB3IC0_F0TG_MB_C_brd_V02_OCP.brd

PC553_4  Q_CAP  1UF 25V 10% X6S  pkg C0402  page 195 : A = SW_P12V_AUX_PVDDCR_CPU0_P0_FLT ; B = GND
R24  Q_RES  4.7K 5% EMPTY  pkg 0402LF  page 238 : A = P3V3_AUX ; B = SMB_CPU_FRU_3V3AUX_SDA

(kicad_pcb
	(version 20260206)
	(generator "pcbnew")
	(generator_version "10.0")
	(general
		(thickness 1.6)
		(legacy_teardrops no)
	)
	(paper "A4")
	(title_block
		(title "04192023_DAF0TMB3IC0_F0TG_MB_C_brd_V02_OCP.brd")
		(comment 1 "Grand Teton / footprints 244-245 of 8354")
	)
	(layers
		(0 "F.Cu" signal "TOP")
		(4 "In1.Cu" signal "GND")
		(6 "In2.Cu" signal "IN1")
		(8 "In3.Cu" signal "GND1")
		(10 "In4.Cu" signal "IN2")
		(12 "In5.Cu" signal "GND2")
		(14 "In6.Cu" signal "IN3")
		(16 "In7.Cu" signal "GND3")
		(18 "In8.Cu" signal "VCC")
		(20 "In9.Cu" signal "VCC1")
		(22 "In10.Cu" signal "GND4")
		(24 "In11.Cu" signal "IN4")
		(26 "In12.Cu" signal "GND5")
		(28 "In13.Cu" signal "IN5")
		(30 "In14.Cu" signal "GND6")
		(32 "In15.Cu" signal "IN6")
		(34 "In16.Cu" signal "GND7")
		(2 "B.Cu" signal "BOTTOM")
		(9 "F.Adhes" user "F.Adhesive")
		(11 "B.Adhes" user "B.Adhesive")
		(13 "F.Paste" user "Package Geometry/Pastemask Top")
		(15 "B.Paste" user "Package Geometry/Pastemask Bottom")
		(5 "F.SilkS" user "Ref Des/Silkscreen Top")
		(7 "B.SilkS" user "Ref Des/Silkscreen Bottom")
		(1 "F.Mask" user "Board Geometry/Soldermask Top")
		(3 "B.Mask" user "Board Geometry/Soldermask Bottom")
		(17 "Dwgs.User" user "User.Drawings")
		(19 "Cmts.User" user "User.Comments")
		(21 "Eco1.User" user "User.Eco1")
		(23 "Eco2.User" user "User.Eco2")
		(25 "Edge.Cuts" user "Board Geometry/Outline")
		(27 "Margin" user)
		(31 "F.CrtYd" user "Package Geometry/Place Bound Top")
		(29 "B.CrtYd" user "Package Geometry/Place Bound Bottom")
		(35 "F.Fab" user "Ref Des/Assembly Top")
		(33 "B.Fab" user "Ref Des/Assembly Bottom")
	)
	(footprint ""
		(layer "F.Cu")
		(at 385.749038 -182.661052 90)
		(property "Reference" "PC553_4"
			(at 0 0 90)
			(layer "F.SilkS")
			(hide yes)
			(effects
				(font
					(size 1.27 1.27)
				)
			)
		)
		(property "Value" ""
			(at 0 0 90)
			(layer "F.Fab")
			(effects
				(font
					(size 1.27 1.27)
				)
			)
		)
		(duplicate_pad_numbers_are_jumpers no)
		(fp_line
			(start 0.7874 -0.4064)
			(end 0.7874 0.4064)
			(stroke
				(width 0.1524)
				(type default)
			)
			(layer "F.SilkS")
		)
		(fp_line
			(start -0.7874 -0.4064)
			(end 0.7874 -0.4064)
			(stroke
				(width 0.1524)
				(type default)
			)
			(layer "F.SilkS")
		)
		(fp_line
			(start 0.7874 0.4064)
			(end -0.7874 0.4064)
			(stroke
				(width 0.1524)
				(type default)
			)
			(layer "F.SilkS")
		)
		(fp_line
			(start -0.7874 0.4064)
			(end -0.7874 -0.4064)
			(stroke
				(width 0.1524)
				(type default)
			)
			(layer "F.SilkS")
		)
		(fp_line
			(start -0.12065 -0.305054)
			(end -0.12065 -0.2794)
			(stroke
				(width 0.1)
				(type default)
			)
			(layer "F.Fab")
		)
		(fp_line
			(start -0.67945 -0.305054)
			(end -0.12065 -0.305054)
			(stroke
				(width 0.1)
				(type default)
			)
			(layer "F.Fab")
		)
		(fp_line
			(start 0.67945 -0.3048)
			(end 0.67945 0.3048)
			(stroke
				(width 0.1)
				(type default)
			)
			(layer "F.Fab")
		)
		(fp_line
			(start 0.12065 -0.3048)
			(end 0.67945 -0.3048)
			(stroke
				(width 0.1)
				(type default)
			)
			(layer "F.Fab")
		)
		(fp_line
			(start 0.12065 -0.2794)
			(end 0.12065 -0.3048)
			(stroke
				(width 0.1)
				(type default)
			)
			(layer "F.Fab")
		)
		(fp_line
			(start -0.12065 -0.2794)
			(end 0.12065 -0.2794)
			(stroke
				(width 0.1)
				(type default)
			)
			(layer "F.Fab")
		)
		(fp_line
			(start 0.120396 0.2794)
			(end -0.12065 0.2794)
			(stroke
				(width 0.1)
				(type default)
			)
			(layer "F.Fab")
		)
		(fp_line
			(start -0.12065 0.2794)
			(end -0.12065 0.3048)
			(stroke
				(width 0.1)
				(type default)
			)
			(layer "F.Fab")
		)
		(fp_line
			(start 0.67945 0.3048)
			(end 0.120396 0.3048)
			(stroke
				(width 0.1)
				(type default)
			)
			(layer "F.Fab")
		)
		(fp_line
			(start 0.120396 0.3048)
			(end 0.120396 0.2794)
			(stroke
				(width 0.1)
				(type default)
			)
			(layer "F.Fab")
		)
		(fp_line
			(start -0.12065 0.3048)
			(end -0.67945 0.3048)
			(stroke
				(width 0.1)
				(type default)
			)
			(layer "F.Fab")
		)
		(fp_line
			(start -0.67945 0.3048)
			(end -0.67945 -0.305054)
			(stroke
				(width 0.1)
				(type default)
			)
			(layer "F.Fab")
		)
		(pad "1" smd circle
			(at -0.40005 0 90)
			(size 0 0)
			(layers "F.Cu" "F.Mask" "F.Paste")
			(net "SW_P12V_AUX_PVDDCR_CPU0_P0_FLT")
		)
		(pad "2" smd circle
			(at 0.40005 0 90)
			(size 0 0)
			(layers "F.Cu" "F.Mask" "F.Paste")
			(net "GND")
		)
	)
	(footprint ""
		(layer "F.Cu")
		(at 314.567316 -109.53877 180)
		(property "Reference" "R24"
			(at 0 0 180)
			(layer "F.SilkS")
			(hide yes)
			(effects
				(font
					(size 1.27 1.27)
				)
			)
		)
		(property "Value" ""
			(at 0 0 180)
			(layer "F.Fab")
			(effects
				(font
					(size 1.27 1.27)
				)
			)
		)
		(duplicate_pad_numbers_are_jumpers no)
		(fp_line
			(start 0.7874 0.4064)
			(end -0.7874 0.4064)
			(stroke
				(width 0.1524)
				(type default)
			)
			(layer "F.SilkS")
		)
		(fp_line
			(start 0.7874 -0.4064)
			(end 0.7874 0.4064)
			(stroke
				(width 0.1524)
				(type default)
			)
			(layer "F.SilkS")
		)
		(fp_line
			(start -0.7874 0.4064)
			(end -0.7874 -0.4064)
			(stroke
				(width 0.1524)
				(type default)
			)
			(layer "F.SilkS")
		)
		(fp_line
			(start -0.7874 -0.4064)
			(end 0.7874 -0.4064)
			(stroke
				(width 0.1524)
				(type default)
			)
			(layer "F.SilkS")
		)
		(fp_line
			(start 0.67945 0.3048)
			(end 0.120396 0.3048)
			(stroke
				(width 0.1)
				(type default)
			)
			(layer "F.Fab")
		)
		(fp_line
			(start 0.67945 -0.3048)
			(end 0.67945 0.3048)
			(stroke
				(width 0.1)
				(type default)
			)
			(layer "F.Fab")
		)
		(fp_line
			(start 0.12065 -0.2794)
			(end 0.12065 -0.3048)
			(stroke
				(width 0.1)
				(type default)
			)
			(layer "F.Fab")
		)
		(fp_line
			(start 0.12065 -0.3048)
			(end 0.67945 -0.3048)
			(stroke
				(width 0.1)
				(type default)
			)
			(layer "F.Fab")
		)
		(fp_line
			(start 0.120396 0.3048)
			(end 0.120396 0.2794)
			(stroke
				(width 0.1)
				(type default)
			)
			(layer "F.Fab")
		)
		(fp_line
			(start 0.120396 0.2794)
			(end -0.12065 0.2794)
			(stroke
				(width 0.1)
				(type default)
			)
			(layer "F.Fab")
		)
		(fp_line
			(start -0.12065 0.3048)
			(end -0.67945 0.3048)
			(stroke
				(width 0.1)
				(type default)
			)
			(layer "F.Fab")
		)
		(fp_line
			(start -0.12065 0.2794)
			(end -0.12065 0.3048)
			(stroke
				(width 0.1)
				(type default)
			)
			(layer "F.Fab")
		)
		(fp_line
			(start -0.12065 -0.2794)
			(end 0.12065 -0.2794)
			(stroke
				(width 0.1)
				(type default)
			)
			(layer "F.Fab")
		)
		(fp_line
			(start -0.12065 -0.305054)
			(end -0.12065 -0.2794)
			(stroke
				(width 0.1)
				(type default)
			)
			(layer "F.Fab")
		)
		(fp_line
			(start -0.67945 0.3048)
			(end -0.67945 -0.305054)
			(stroke
				(width 0.1)
				(type default)
			)
			(layer "F.Fab")
		)
		(fp_line
			(start -0.67945 -0.305054)
			(end -0.12065 -0.305054)
			(stroke
				(width 0.1)
				(type default)
			)
			(layer "F.Fab")
		)
		(pad "1" smd circle
			(at -0.40005 0 180)
			(size 0 0)
			(layers "F.Cu" "F.Mask" "F.Paste")
			(net "P3V3_AUX")
		)
		(pad "2" smd circle
			(at 0.40005 0 180)
			(size 0 0)
			(layers "F.Cu" "F.Mask" "F.Paste")
			(net "SMB_CPU_FRU_3V3AUX_SDA")
		)
	)
)
